# T6G (Grand Teton) — schematic netlist excerpt (pin names and nets, part order shuffled) for the footprints in the layout excerpt that follows; sources: Cadence DE-HDL packaged netlist, KiCad conversion of 04192023_DAF0TMB3IC0_F0TG_MB_C_brd_V02_OCP.brd

PL77  Q_INDUCTOR  BLM18SN220TN1D/8000MA IND  pkg SMLF  page 209 : \1\ = P12V_AUX ; \2\ = SW_P12V_AUX_PVDD18_S5_P0_FLT
R120  Q_RES  33 5% CHIP  pkg 0402LF  page 207 : A = PVDD11_S3_P0_PMALERT ; B = PVDD11_S3_P0_PMALERT_R

(kicad_pcb
	(version 20260206)
	(generator "pcbnew")
	(generator_version "10.0")
	(general
		(thickness 1.6)
		(legacy_teardrops no)
	)
	(paper "A4")
	(title_block
		(title "04192023_DAF0TMB3IC0_F0TG_MB_C_brd_V02_OCP.brd")
		(comment 1 "Grand Teton / footprints 4173-4174 of 8354")
	)
	(layers
		(0 "F.Cu" signal "TOP")
		(4 "In1.Cu" signal "GND")
		(6 "In2.Cu" signal "IN1")
		(8 "In3.Cu" signal "GND1")
		(10 "In4.Cu" signal "IN2")
		(12 "In5.Cu" signal "GND2")
		(14 "In6.Cu" signal "IN3")
		(16 "In7.Cu" signal "GND3")
		(18 "In8.Cu" signal "VCC")
		(20 "In9.Cu" signal "VCC1")
		(22 "In10.Cu" signal "GND4")
		(24 "In11.Cu" signal "IN4")
		(26 "In12.Cu" signal "GND5")
		(28 "In13.Cu" signal "IN5")
		(30 "In14.Cu" signal "GND6")
		(32 "In15.Cu" signal "IN6")
		(34 "In16.Cu" signal "GND7")
		(2 "B.Cu" signal "BOTTOM")
		(9 "F.Adhes" user "F.Adhesive")
		(11 "B.Adhes" user "B.Adhesive")
		(13 "F.Paste" user "Package Geometry/Pastemask Top")
		(15 "B.Paste" user "Package Geometry/Pastemask Bottom")
		(5 "F.SilkS" user "Ref Des/Silkscreen Top")
		(7 "B.SilkS" user "Ref Des/Silkscreen Bottom")
		(1 "F.Mask" user "Board Geometry/Soldermask Top")
		(3 "B.Mask" user "Board Geometry/Soldermask Bottom")
		(17 "Dwgs.User" user "User.Drawings")
		(19 "Cmts.User" user "User.Comments")
		(21 "Eco1.User" user "User.Eco1")
		(23 "Eco2.User" user "User.Eco2")
		(25 "Edge.Cuts" user "Board Geometry/Outline")
		(27 "Margin" user)
		(31 "F.CrtYd" user "Package Geometry/Place Bound Top")
		(29 "B.CrtYd" user "Package Geometry/Place Bound Bottom")
		(35 "F.Fab" user "Ref Des/Assembly Top")
		(33 "B.Fab" user "Ref Des/Assembly Bottom")
	)
	(footprint ""
		(layer "F.Cu")
		(at 332.8924 -131.755642)
		(property "Reference" "PL77"
			(at 0 0 0)
			(layer "F.SilkS")
			(hide yes)
			(effects
				(font
					(size 1.27 1.27)
				)
			)
		)
		(property "Value" ""
			(at 0 0 0)
			(layer "F.Fab")
			(effects
				(font
					(size 1.27 1.27)
				)
			)
		)
		(duplicate_pad_numbers_are_jumpers no)
		(fp_line
			(start -1.27 -0.5842)
			(end 1.27 -0.5842)
			(stroke
				(width 0.1524)
				(type default)
			)
			(layer "F.SilkS")
		)
		(fp_line
			(start -1.27 -0.5588)
			(end -1.27 -0.5842)
			(stroke
				(width 0.1524)
				(type default)
			)
			(layer "F.SilkS")
		)
		(fp_line
			(start -1.27 0.5842)
			(end -1.27 -0.5842)
			(stroke
				(width 0.1524)
				(type default)
			)
			(layer "F.SilkS")
		)
		(fp_line
			(start 1.27 0.5842)
			(end -1.27 0.5842)
			(stroke
				(width 0.1524)
				(type default)
			)
			(layer "F.SilkS")
		)
		(fp_line
			(start 1.27 0.5842)
			(end 1.27 -0.5842)
			(stroke
				(width 0.1524)
				(type default)
			)
			(layer "F.SilkS")
		)
		(fp_line
			(start -1.194308 -0.406654)
			(end -0.9144 -0.406654)
			(stroke
				(width 0.1)
				(type default)
			)
			(layer "F.Fab")
		)
		(fp_line
			(start -1.194308 0.406654)
			(end -1.194308 -0.406654)
			(stroke
				(width 0.1)
				(type default)
			)
			(layer "F.Fab")
		)
		(fp_line
			(start -0.9144 -0.508)
			(end 0.9144 -0.508)
			(stroke
				(width 0.1)
				(type default)
			)
			(layer "F.Fab")
		)
		(fp_line
			(start -0.9144 -0.406654)
			(end -0.9144 -0.508)
			(stroke
				(width 0.1)
				(type default)
			)
			(layer "F.Fab")
		)
		(fp_line
			(start -0.9144 0.406654)
			(end -1.194308 0.406654)
			(stroke
				(width 0.1)
				(type default)
			)
			(layer "F.Fab")
		)
		(fp_line
			(start -0.9144 0.508)
			(end -0.9144 0.406654)
			(stroke
				(width 0.1)
				(type default)
			)
			(layer "F.Fab")
		)
		(fp_line
			(start 0.9144 -0.508)
			(end 0.9144 -0.406654)
			(stroke
				(width 0.1)
				(type default)
			)
			(layer "F.Fab")
		)
		(fp_line
			(start 0.9144 -0.406654)
			(end 1.1938 -0.406654)
			(stroke
				(width 0.1)
				(type default)
			)
			(layer "F.Fab")
		)
		(fp_line
			(start 0.9144 0.4064)
			(end 0.9144 0.508)
			(stroke
				(width 0.1)
				(type default)
			)
			(layer "F.Fab")
		)
		(fp_line
			(start 0.9144 0.508)
			(end -0.9144 0.508)
			(stroke
				(width 0.1)
				(type default)
			)
			(layer "F.Fab")
		)
		(fp_line
			(start 1.1938 -0.406654)
			(end 1.1938 0.4064)
			(stroke
				(width 0.1)
				(type default)
			)
			(layer "F.Fab")
		)
		(fp_line
			(start 1.1938 0.4064)
			(end 0.9144 0.4064)
			(stroke
				(width 0.1)
				(type default)
			)
			(layer "F.Fab")
		)
		(pad "1" smd rect
			(at -0.7366 0 270)
			(size 0.7112 0.8128)
			(layers "F.Cu" "F.Mask" "F.Paste")
			(net "P12V_AUX")
		)
		(pad "2" smd rect
			(at 0.7366 0 270)
			(size 0.7112 0.8128)
			(layers "F.Cu" "F.Mask" "F.Paste")
			(net "SW_P12V_AUX_PVDD18_S5_P0_FLT")
		)
	)
	(footprint ""
		(layer "F.Cu")
		(at 415.586418 -365.881412 -90)
		(property "Reference" "R120"
			(at 0 0 270)
			(layer "F.SilkS")
			(hide yes)
			(effects
				(font
					(size 1.27 1.27)
				)
			)
		)
		(property "Value" ""
			(at 0 0 270)
			(layer "F.Fab")
			(effects
				(font
					(size 1.27 1.27)
				)
			)
		)
		(duplicate_pad_numbers_are_jumpers no)
		(fp_line
			(start -0.7874 0.4064)
			(end -0.7874 -0.4064)
			(stroke
				(width 0.1524)
				(type default)
			)
			(layer "F.SilkS")
		)
		(fp_line
			(start 0.7874 0.4064)
			(end -0.7874 0.4064)
			(stroke
				(width 0.1524)
				(type default)
			)
			(layer "F.SilkS")
		)
		(fp_line
			(start -0.7874 -0.4064)
			(end 0.7874 -0.4064)
			(stroke
				(width 0.1524)
				(type default)
			)
			(layer "F.SilkS")
		)
		(fp_line
			(start 0.7874 -0.4064)
			(end 0.7874 0.4064)
			(stroke
				(width 0.1524)
				(type default)
			)
			(layer "F.SilkS")
		)
		(fp_line
			(start -0.67945 0.3048)
			(end -0.67945 -0.305054)
			(stroke
				(width 0.1)
				(type default)
			)
			(layer "F.Fab")
		)
		(fp_line
			(start -0.12065 0.3048)
			(end -0.67945 0.3048)
			(stroke
				(width 0.1)
				(type default)
			)
			(layer "F.Fab")
		)
		(fp_line
			(start 0.120396 0.3048)
			(end 0.120396 0.2794)
			(stroke
				(width 0.1)
				(type default)
			)
			(layer "F.Fab")
		)
		(fp_line
			(start 0.67945 0.3048)
			(end 0.120396 0.3048)
			(stroke
				(width 0.1)
				(type default)
			)
			(layer "F.Fab")
		)
		(fp_line
			(start -0.12065 0.2794)
			(end -0.12065 0.3048)
			(stroke
				(width 0.1)
				(type default)
			)
			(layer "F.Fab")
		)
		(fp_line
			(start 0.120396 0.2794)
			(end -0.12065 0.2794)
			(stroke
				(width 0.1)
				(type default)
			)
			(layer "F.Fab")
		)
		(fp_line
			(start -0.12065 -0.2794)
			(end 0.12065 -0.2794)
			(stroke
				(width 0.1)
				(type default)
			)
			(layer "F.Fab")
		)
		(fp_line
			(start 0.12065 -0.2794)
			(end 0.12065 -0.3048)
			(stroke
				(width 0.1)
				(type default)
			)
			(layer "F.Fab")
		)
		(fp_line
			(start 0.12065 -0.3048)
			(end 0.67945 -0.3048)
			(stroke
				(width 0.1)
				(type default)
			)
			(layer "F.Fab")
		)
		(fp_line
			(start 0.67945 -0.3048)
			(end 0.67945 0.3048)
			(stroke
				(width 0.1)
				(type default)
			)
			(layer "F.Fab")
		)
		(fp_line
			(start -0.67945 -0.305054)
			(end -0.12065 -0.305054)
			(stroke
				(width 0.1)
				(type default)
			)
			(layer "F.Fab")
		)
		(fp_line
			(start -0.12065 -0.305054)
			(end -0.12065 -0.2794)
			(stroke
				(width 0.1)
				(type default)
			)
			(layer "F.Fab")
		)
		(pad "1" smd circle
			(at -0.40005 0 270)
			(size 0 0)
			(layers "F.Cu" "F.Mask" "F.Paste")
			(net "PVDD11_S3_P0_PMALERT")
		)
		(pad "2" smd circle
			(at 0.40005 0 270)
			(size 0 0)
			(layers "F.Cu" "F.Mask" "F.Paste")
			(net "PVDD11_S3_P0_PMALERT_R")
		)
	)
)
